FILE_TYPE = MACRO_DRAWING;
SET COLOR_WIRE YELLOW;
SET COLOR_PROP MONO;
SET COLOR_DOT WHITE;
SET COLOR_ARC YELLOW;
SET COLOR_BODY GREEN;
SET COLOR_NOTE MONO;
SET PROP_DISPLAY VALUE;
SET PAGE_NUMBER P162;
FORCEADD P3V3_STBY..1
(5250 3700);
FORCEPROP 3 LASTPIN (5250 3650) SIG_NAME P3V3_STBY\g
J 0
(5260 3660);
DISPLAY 0.659574 (5260 3660);
PAINT MONO (5260 3660);
DISPLAY INVISIBLE (5260 3660);
FORCEPROP 1 LAST VOLTAGE 3.3V
J 0
(5205 3657);
DISPLAY 0.340426 (5205 3657);
PAINT SKYBLUE (5205 3657);
DISPLAY INVISIBLE (5205 3657);
FORCEPROP 2 LAST CDS_LIB mstr_symbols
J 0
(5250 3700);
PAINT ORANGE (5250 3700);
DISPLAY INVISIBLE (5250 3700);
FORCEPROP 1 LAST SIZE 1B
J 0
(5295 3722);
DISPLAY 0.340426 (5295 3722);
PAINT GREEN (5295 3722);
DISPLAY INVISIBLE (5295 3722);
FORCEPROP 1 LAST PATH I10
J 0
(5295 3702);
DISPLAY 0.340426 (5295 3702);
PAINT GREEN (5295 3702);
DISPLAY INVISIBLE (5295 3702);
FORCEPROP 1 LAST BODY_TYPE PLUMBING
J 0
(5205 3657);
DISPLAY 0.340426 (5205 3657);
PAINT GREEN (5205 3657);
DISPLAY INVISIBLE (5205 3657);
FORCEPROP 1 LAST HDL_POWER P3V3_STBY
J 0
(4950 3575);
DISPLAY 0.872340 (4950 3575);
PAINT ORANGE (4950 3575);
DISPLAY INVISIBLE (4950 3575);
FORCEADD RES..1
(5075 2550);
FORCEPROP 1 LAST LOCATION R8F12
J 0
(4768 2557);
DISPLAY 0.617021 (4768 2557);
PAINT AQUA (4768 2557);
FORCEPROP 1 LASTPIN (5175 2550) $PN 2
J 0
(5137 2562);
DISPLAY 0.617021 (5137 2562);
PAINT MONO (5137 2562);
FORCEPROP 1 LASTPIN (4975 2550) $PN 1
J 0
(4987 2562);
DISPLAY 0.617021 (4987 2562);
PAINT MONO (4987 2562);
FORCEPROP 1 LAST VALUE 33.2
J 0
(4750 2507);
DISPLAY 0.617021 (4750 2507);
PAINT SKYBLUE (4750 2507);
FORCEPROP 1 LAST TOLERANCE 1%
J 0
(4900 2500);
DISPLAY 0.638298 (4900 2500);
PAINT SKYBLUE (4900 2500);
FORCEPROP 1 LAST MATERIAL CHIP
J 0
(5000 2500);
DISPLAY 0.638298 (5000 2500);
PAINT SKYBLUE (5000 2500);
FORCEPROP 1 LAST PART_NUMBER G21796-074
J 0
(5150 2500);
DISPLAY 0.638298 (5150 2500);
PAINT BLUE (5150 2500);
FORCEPROP 1 LAST PACK_TYPE 0402
J 0
(5600 2500);
DISPLAY 0.638298 (5600 2500);
PAINT SKYBLUE (5600 2500);
FORCEPROP 1 LAST WATTAGE 1/16W
J 0
(5400 2500);
DISPLAY 0.638298 (5400 2500);
PAINT SKYBLUE (5400 2500);
FORCEPROP 2 LAST CDS_LOCATION R8F12
J 0
(4768 2557);
DISPLAY 0.617021 (4768 2557);
PAINT AQUA (4768 2557);
DISPLAY INVISIBLE (4768 2557);
FORCEPROP 2 LAST CDS_LIB mstr_discrete
J 1
(5075 2550);
PAINT ORANGE (5075 2550);
DISPLAY INVISIBLE (5075 2550);
FORCEPROP 2 LAST SEC_TYPE 0402
J 0
(5025 2775);
DISPLAY 1.021277 (5025 2775);
PAINT ORANGE (5025 2775);
DISPLAY INVISIBLE (5025 2775);
FORCEPROP 2 LAST SEC 1
J 0
(5025 2775);
DISPLAY 0.680851 (5025 2775);
PAINT MONO (5025 2775);
DISPLAY INVISIBLE (5025 2775);
FORCEPROP 1 LAST PATH I13
J 0
(5025 2700);
DISPLAY 0.978723 (5025 2700);
PAINT WHITE (5025 2700);
DISPLAY INVISIBLE (5025 2700);
FORCEPROP 2 LAST ROOM BMC_BOOT_SPI
J 0
(5300 2600);
DISPLAY 1.021277 (5300 2600);
PAINT ORANGE (5300 2600);
DISPLAY INVISIBLE (5300 2600);
FORCEPROP 2 LAST BOM_COST SM_MEM
J 0
(5300 2650);
DISPLAY 1.021277 (5300 2650);
PAINT ORANGE (5300 2650);
DISPLAY INVISIBLE (5300 2650);
FORCEADD OFFPAGE..1
(4200 2850);
FORCEPROP 2 LAST $XR2 246 
J 0
(3708 2850);
DISPLAY 0.638298 (3708 2850);
PAINT MONO (3708 2850);
FORCEPROP 2 LAST $XR1 150 
J 0
(3828 2850);
DISPLAY 0.638298 (3828 2850);
PAINT MONO (3828 2850);
FORCEPROP 2 LAST $XR0 146 
J 0
(3948 2850);
DISPLAY 0.638298 (3948 2850);
PAINT MONO (3948 2850);
FORCEPROP 2 LAST PATH I16
J 0
(3950 2900);
DISPLAY 1.021277 (3950 2900);
PAINT ORANGE (3950 2900);
DISPLAY INVISIBLE (3950 2900);
FORCEPROP 2 LAST CDS_LIB mstr_standard
J 0
(4200 2850);
DISPLAY 1.531915 (4200 2850);
PAINT ORANGE (4200 2850);
DISPLAY INVISIBLE (4200 2850);
FORCEPROP 1 LAST OFFPAGE TRUE
J 0
(4525 2725);
PAINT GREEN (4525 2725);
DISPLAY INVISIBLE (4525 2725);
FORCEPROP 1 LAST COMMENT_BODY TRUE
J 0
(4325 2750);
DISPLAY 0.978723 (4325 2750);
PAINT PEACH (4325 2750);
DISPLAY INVISIBLE (4325 2750);
FORCEADD OFFPAGE..1
(4200 2800);
FORCEPROP 2 LAST $XR0 146 
J 0
(3948 2800);
DISPLAY 0.638298 (3948 2800);
PAINT MONO (3948 2800);
FORCEPROP 2 LAST PATH I17
J 0
(3950 2850);
DISPLAY 1.021277 (3950 2850);
PAINT ORANGE (3950 2850);
DISPLAY INVISIBLE (3950 2850);
FORCEPROP 2 LAST CDS_LIB mstr_standard
J 0
(4200 2800);
DISPLAY 1.531915 (4200 2800);
PAINT ORANGE (4200 2800);
DISPLAY INVISIBLE (4200 2800);
FORCEPROP 1 LAST OFFPAGE TRUE
J 0
(4525 2675);
PAINT GREEN (4525 2675);
DISPLAY INVISIBLE (4525 2675);
FORCEPROP 1 LAST COMMENT_BODY TRUE
J 0
(4325 2700);
DISPLAY 0.978723 (4325 2700);
PAINT PEACH (4325 2700);
DISPLAY INVISIBLE (4325 2700);
FORCEADD OFFPAGE..5
(4200 2550);
FORCEPROP 2 LAST $XR2 150 
J 0
(3705 2550);
DISPLAY 0.638298 (3705 2550);
PAINT MONO (3705 2550);
FORCEPROP 2 LAST $XR1 146 
J 0
(3825 2550);
DISPLAY 0.638298 (3825 2550);
PAINT MONO (3825 2550);
FORCEPROP 2 LAST $XR0 246 
J 0
(3945 2550);
DISPLAY 0.638298 (3945 2550);
PAINT MONO (3945 2550);
FORCEPROP 2 LAST PATH I19
J 0
(3925 2600);
DISPLAY 1.021277 (3925 2600);
PAINT ORANGE (3925 2600);
DISPLAY INVISIBLE (3925 2600);
FORCEPROP 2 LAST CDS_LIB mstr_standard
J 1
(4200 2550);
PAINT ORANGE (4200 2550);
DISPLAY INVISIBLE (4200 2550);
FORCEPROP 1 LAST OFFPAGE TRUE
J 0
(4525 2425);
PAINT GREEN (4525 2425);
DISPLAY INVISIBLE (4525 2425);
FORCEPROP 1 LAST COMMENT_BODY TRUE
J 0
(4300 2475);
DISPLAY 1.170213 (4300 2475);
PAINT GREEN (4300 2475);
DISPLAY INVISIBLE (4300 2475);
FORCEADD OFFPAGE..1
(4200 2500);
FORCEPROP 2 LAST $XR2 246 
J 0
(3708 2500);
DISPLAY 0.638298 (3708 2500);
PAINT MONO (3708 2500);
FORCEPROP 2 LAST $XR1 150 
J 0
(3828 2500);
DISPLAY 0.638298 (3828 2500);
PAINT MONO (3828 2500);
FORCEPROP 2 LAST $XR0 146 
J 0
(3948 2500);
DISPLAY 0.638298 (3948 2500);
PAINT MONO (3948 2500);
FORCEPROP 2 LAST PATH I21
J 0
(3925 2550);
DISPLAY 1.021277 (3925 2550);
PAINT ORANGE (3925 2550);
DISPLAY INVISIBLE (3925 2550);
FORCEPROP 2 LAST CDS_LIB mstr_standard
J 0
(4200 2500);
DISPLAY 1.531915 (4200 2500);
PAINT ORANGE (4200 2500);
DISPLAY INVISIBLE (4200 2500);
FORCEPROP 1 LAST OFFPAGE TRUE
J 0
(4525 2375);
PAINT GREEN (4525 2375);
DISPLAY INVISIBLE (4525 2375);
FORCEPROP 1 LAST COMMENT_BODY TRUE
J 0
(4325 2400);
DISPLAY 0.978723 (4325 2400);
PAINT PEACH (4325 2400);
DISPLAY INVISIBLE (4325 2400);
FORCEADD RES..2
R 2
(4825 3325);
FORCEPROP 1 LASTPIN (4825 3225) $PN 2
J 2
(4820 3235);
DISPLAY 0.787234 (4820 3235);
PAINT ORANGE (4820 3235);
FORCEPROP 1 LASTPIN (4825 3425) $PN 1
J 2
(4820 3387);
DISPLAY 0.787234 (4820 3387);
PAINT ORANGE (4820 3387);
FORCEPROP 1 LAST TOLERANCE 1%
J 2
(4780 3300);
DISPLAY 0.617021 (4780 3300);
PAINT SKYBLUE (4780 3300);
FORCEPROP 1 LAST LOCATION R8F34
J 2
(4780 3450);
DISPLAY 0.617021 (4780 3450);
PAINT AQUA (4780 3450);
FORCEPROP 1 LAST VALUE 4.75K
J 2
(4780 3400);
DISPLAY 0.617021 (4780 3400);
PAINT SKYBLUE (4780 3400);
FORCEPROP 1 LAST MATERIAL CHIP
J 2
(4785 3350);
DISPLAY 0.617021 (4785 3350);
PAINT SKYBLUE (4785 3350);
FORCEPROP 1 LAST WATTAGE 1/16W
J 2
(4785 3250);
DISPLAY 0.617021 (4785 3250);
PAINT SKYBLUE (4785 3250);
FORCEPROP 1 LAST PACK_TYPE 0402
J 2
(4785 3150);
DISPLAY 0.617021 (4785 3150);
PAINT SKYBLUE (4785 3150);
FORCEPROP 1 LAST PART_NUMBER G21796-072
J 2
(4785 3200);
DISPLAY 0.617021 (4785 3200);
PAINT BLUE (4785 3200);
FORCEPROP 1 LAST PATH I22
J 2
(4775 3500);
DISPLAY 0.978723 (4775 3500);
PAINT WHITE (4775 3500);
DISPLAY INVISIBLE (4775 3500);
FORCEPROP 2 LAST SEC_TYPE 0402
J 0
(4775 3550);
DISPLAY 1.021277 (4775 3550);
PAINT ORANGE (4775 3550);
DISPLAY INVISIBLE (4775 3550);
FORCEPROP 2 LAST SEC 1
J 0
(4775 3550);
PAINT MONO (4775 3550);
DISPLAY INVISIBLE (4775 3550);
FORCEPROP 2 LAST BOM_COST SM_MEM
J 0
(4800 3550);
DISPLAY 1.021277 (4800 3550);
PAINT ORANGE (4800 3550);
DISPLAY INVISIBLE (4800 3550);
FORCEPROP 2 LAST ROOM BMC_BOOT_SPI
J 0
(4800 3500);
DISPLAY 1.021277 (4800 3500);
PAINT ORANGE (4800 3500);
DISPLAY INVISIBLE (4800 3500);
FORCEPROP 2 LAST CDS_LOCATION R8F34
J 2
(4780 3450);
DISPLAY 0.617021 (4780 3450);
PAINT AQUA (4780 3450);
DISPLAY INVISIBLE (4780 3450);
FORCEPROP 2 LAST CDS_LIB mstr_discrete
J 0
(4825 3325);
PAINT ORANGE (4825 3325);
DISPLAY INVISIBLE (4825 3325);
FORCEADD RES..2
(4875 2050);
FORCEPROP 1 LASTPIN (4875 1950) $PN 2
J 0
(4880 1960);
DISPLAY 0.787234 (4880 1960);
PAINT ORANGE (4880 1960);
FORCEPROP 1 LAST TOLERANCE 1%
J 0
(4920 2075);
DISPLAY 0.617021 (4920 2075);
PAINT SKYBLUE (4920 2075);
FORCEPROP 1 LAST PACK_TYPE 0402
J 0
(4915 1875);
DISPLAY 0.617021 (4915 1875);
PAINT SKYBLUE (4915 1875);
FORCEPROP 1 LASTPIN (4875 2150) $PN 1
J 0
(4880 2112);
DISPLAY 0.787234 (4880 2112);
PAINT ORANGE (4880 2112);
FORCEPROP 1 LAST PART_NUMBER G21796-026
J 0
(4915 1925);
DISPLAY 0.617021 (4915 1925);
PAINT BLUE (4915 1925);
FORCEPROP 1 LAST MATERIAL EMPTY
J 0
(4915 1975);
DISPLAY 0.617021 (4915 1975);
PAINT RED (4915 1975);
FORCEPROP 1 LAST WATTAGE 1/16W
J 0
(4915 2025);
DISPLAY 0.617021 (4915 2025);
PAINT SKYBLUE (4915 2025);
FORCEPROP 1 LAST VALUE 1.00K
J 0
(4920 2125);
DISPLAY 0.617021 (4920 2125);
PAINT SKYBLUE (4920 2125);
FORCEPROP 1 LAST LOCATION R8F35
J 0
(4920 2175);
DISPLAY 0.617021 (4920 2175);
PAINT AQUA (4920 2175);
FORCEPROP 2 LAST CDS_LIB mstr_discrete
J 0
(4875 2050);
PAINT ORANGE (4875 2050);
DISPLAY INVISIBLE (4875 2050);
FORCEPROP 2 LAST CDS_LOCATION R8F35
J 0
(4920 2175);
DISPLAY 0.617021 (4920 2175);
PAINT AQUA (4920 2175);
DISPLAY INVISIBLE (4920 2175);
FORCEPROP 2 LAST ROOM BMC_BOOT_SPI
J 0
(4925 2225);
DISPLAY 1.021277 (4925 2225);
PAINT ORANGE (4925 2225);
DISPLAY INVISIBLE (4925 2225);
FORCEPROP 1 LAST PATH I24
J 0
(4925 2225);
DISPLAY 0.978723 (4925 2225);
PAINT WHITE (4925 2225);
DISPLAY INVISIBLE (4925 2225);
FORCEPROP 2 LAST BOM_COST SM_MEM
J 0
(4925 2275);
DISPLAY 1.021277 (4925 2275);
PAINT ORANGE (4925 2275);
DISPLAY INVISIBLE (4925 2275);
FORCEPROP 2 LAST SEC 1
J 0
(4925 2275);
PAINT MONO (4925 2275);
DISPLAY INVISIBLE (4925 2275);
FORCEPROP 2 LAST SEC_TYPE 0402
J 0
(4925 2275);
DISPLAY 1.021277 (4925 2275);
PAINT ORANGE (4925 2275);
DISPLAY INVISIBLE (4925 2275);
FORCEADD CAP_A..1
(7650 3400);
FORCEPROP 1 LAST MATERIAL X7R
J 0
(7700 3300);
DISPLAY 0.617021 (7700 3300);
PAINT SKYBLUE (7700 3300);
FORCEPROP 1 LAST LOCATION C8F5
J 0
(7700 3500);
DISPLAY 0.617021 (7700 3500);
PAINT AQUA (7700 3500);
FORCEPROP 1 LAST PART_NUMBER A36096-045
J 0
(7700 3250);
DISPLAY 0.617021 (7700 3250);
PAINT BLUE (7700 3250);
FORCEPROP 1 LAST TOLERANCE 10%
J 0
(7700 3350);
DISPLAY 0.617021 (7700 3350);
PAINT SKYBLUE (7700 3350);
FORCEPROP 1 LASTPIN (7650 3300) $PN 2
J 0
(7660 3280);
DISPLAY 0.787234 (7660 3280);
PAINT ORANGE (7660 3280);
FORCEPROP 1 LASTPIN (7650 3500) $PN 1
J 0
(7660 3480);
DISPLAY 0.787234 (7660 3480);
PAINT ORANGE (7660 3480);
FORCEPROP 1 LAST PACK_TYPE 0402V
J 0
(7700 3200);
DISPLAY 0.617021 (7700 3200);
PAINT SKYBLUE (7700 3200);
FORCEPROP 1 LAST VOLTAGE 25V
J 0
(7700 3400);
DISPLAY 0.617021 (7700 3400);
PAINT SKYBLUE (7700 3400);
FORCEPROP 1 LAST VALUE 0.01UF
J 0
(7700 3450);
DISPLAY 0.617021 (7700 3450);
PAINT SKYBLUE (7700 3450);
FORCEPROP 2 LAST CDS_LIB dev_discrete
J 0
(7650 3400);
PAINT ORANGE (7650 3400);
DISPLAY INVISIBLE (7650 3400);
FORCEPROP 2 LAST CDS_LOCATION C8F5
J 0
(7700 3500);
DISPLAY 0.617021 (7700 3500);
PAINT AQUA (7700 3500);
DISPLAY INVISIBLE (7700 3500);
FORCEPROP 2 LAST ROOM BMC_BOOT_SPI
J 0
(7700 3550);
DISPLAY 1.021277 (7700 3550);
PAINT ORANGE (7700 3550);
DISPLAY INVISIBLE (7700 3550);
FORCEPROP 1 LAST PATH I28
J 0
(7700 3550);
DISPLAY 0.978723 (7700 3550);
PAINT WHITE (7700 3550);
DISPLAY INVISIBLE (7700 3550);
FORCEPROP 2 LAST BOM_COST SM_MEM
J 0
(7700 3600);
DISPLAY 1.021277 (7700 3600);
PAINT ORANGE (7700 3600);
DISPLAY INVISIBLE (7700 3600);
FORCEPROP 2 LAST SEC 1
J 0
(7700 3600);
PAINT MONO (7700 3600);
DISPLAY INVISIBLE (7700 3600);
FORCEPROP 2 LAST SEC_TYPE 0402V
J 0
(7700 3600);
DISPLAY 1.021277 (7700 3600);
PAINT ORANGE (7700 3600);
DISPLAY INVISIBLE (7700 3600);
FORCEADD CAP_A..1
(7350 3400);
FORCEPROP 1 LAST VOLTAGE 6.3V
J 0
(7400 3400);
DISPLAY 0.617021 (7400 3400);
PAINT SKYBLUE (7400 3400);
FORCEPROP 1 LAST VALUE 1.0UF
J 0
(7400 3450);
DISPLAY 0.617021 (7400 3450);
PAINT SKYBLUE (7400 3450);
FORCEPROP 1 LAST LOCATION C8F4
J 0
(7400 3500);
DISPLAY 0.617021 (7400 3500);
PAINT AQUA (7400 3500);
FORCEPROP 1 LAST MATERIAL X6S
J 0
(7400 3300);
DISPLAY 0.617021 (7400 3300);
PAINT SKYBLUE (7400 3300);
FORCEPROP 1 LAST TOLERANCE 10%
J 0
(7400 3350);
DISPLAY 0.617021 (7400 3350);
PAINT SKYBLUE (7400 3350);
FORCEPROP 1 LASTPIN (7350 3300) $PN 2
J 0
(7360 3280);
DISPLAY 0.787234 (7360 3280);
PAINT ORANGE (7360 3280);
FORCEPROP 1 LASTPIN (7350 3500) $PN 1
J 0
(7360 3480);
DISPLAY 0.787234 (7360 3480);
PAINT ORANGE (7360 3480);
FORCEPROP 1 LAST PACK_TYPE 0402V
J 0
(7400 3200);
DISPLAY 0.617021 (7400 3200);
PAINT SKYBLUE (7400 3200);
FORCEPROP 1 LAST PART_NUMBER D97712-004
J 0
(7400 3250);
DISPLAY 0.617021 (7400 3250);
PAINT BLUE (7400 3250);
FORCEPROP 2 LAST CDS_LIB dev_discrete
J 0
(7350 3400);
PAINT ORANGE (7350 3400);
DISPLAY INVISIBLE (7350 3400);
FORCEPROP 2 LAST CDS_LOCATION C8F4
J 0
(7400 3500);
DISPLAY 0.617021 (7400 3500);
PAINT AQUA (7400 3500);
DISPLAY INVISIBLE (7400 3500);
FORCEPROP 2 LAST ROOM BMC_BOOT_SPI
J 0
(7400 3550);
DISPLAY 1.021277 (7400 3550);
PAINT ORANGE (7400 3550);
DISPLAY INVISIBLE (7400 3550);
FORCEPROP 1 LAST PATH I30
J 0
(7400 3550);
DISPLAY 0.978723 (7400 3550);
PAINT WHITE (7400 3550);
DISPLAY INVISIBLE (7400 3550);
FORCEPROP 2 LAST BOM_COST SM_MEM
J 0
(7400 3600);
DISPLAY 1.021277 (7400 3600);
PAINT ORANGE (7400 3600);
DISPLAY INVISIBLE (7400 3600);
FORCEPROP 2 LAST SEC 1
J 0
(7400 3600);
PAINT MONO (7400 3600);
DISPLAY INVISIBLE (7400 3600);
FORCEPROP 2 LAST SEC_TYPE 0402V
J 0
(7400 3600);
DISPLAY 1.021277 (7400 3600);
PAINT ORANGE (7400 3600);
DISPLAY INVISIBLE (7400 3600);
FORCEADD GND..1
(7650 3075);
FORCEPROP 3 LASTPIN (7650 3125) SIG_NAME GND\g
J 0
(7660 3135);
DISPLAY 0.659574 (7660 3135);
PAINT MONO (7660 3135);
DISPLAY INVISIBLE (7660 3135);
FORCEPROP 1 LAST VOLTAGE 0.0V
J 0
(7605 3032);
DISPLAY 0.340426 (7605 3032);
PAINT SKYBLUE (7605 3032);
DISPLAY INVISIBLE (7605 3032);
FORCEPROP 1 LAST SIZE 1B
J 0
(7725 3025);
DISPLAY 0.872340 (7725 3025);
PAINT AQUA (7725 3025);
DISPLAY INVISIBLE (7725 3025);
FORCEPROP 2 LAST CDS_LIB mstr_symbols
J 0
(7650 3075);
PAINT ORANGE (7650 3075);
DISPLAY INVISIBLE (7650 3075);
FORCEPROP 1 LAST PATH I31
J 0
(7725 3075);
DISPLAY 0.872340 (7725 3075);
PAINT AQUA (7725 3075);
DISPLAY INVISIBLE (7725 3075);
FORCEPROP 1 LAST BODY_TYPE PLUMBING
J 0
(7605 3032);
DISPLAY 0.340426 (7605 3032);
PAINT GREEN (7605 3032);
DISPLAY INVISIBLE (7605 3032);
FORCEPROP 1 LAST HDL_POWER GND
J 0
(7650 3225);
DISPLAY 0.872340 (7650 3225);
PAINT GREEN (7650 3225);
DISPLAY INVISIBLE (7650 3225);
FORCEADD W25Q128..3
(6450 2800);
FORCEPROP 2 LASTPIN (5900 2500) $PN 15
J 2
(5890 2510);
DISPLAY 0.617021 (5890 2510);
PAINT ORANGE (5890 2510);
FORCEPROP 2 LASTPIN (5900 2550) $PN 8
J 2
(5890 2560);
DISPLAY 0.617021 (5890 2560);
PAINT ORANGE (5890 2560);
FORCEPROP 2 LASTPIN (5900 2800) $PN 7
J 2
(5890 2810);
DISPLAY 0.617021 (5890 2810);
PAINT ORANGE (5890 2810);
FORCEPROP 2 LASTPIN (5900 2900) $PN 3
J 2
(5890 2910);
DISPLAY 0.617021 (5890 2910);
PAINT ORANGE (5890 2910);
FORCEPROP 2 LASTPIN (5900 3000) $PN 2
J 2
(5890 3010);
DISPLAY 0.617021 (5890 3010);
PAINT ORANGE (5890 3010);
FORCEPROP 2 LASTPIN (5900 2600) $PN 9
J 2
(5890 2610);
DISPLAY 0.617021 (5890 2610);
PAINT ORANGE (5890 2610);
FORCEPROP 2 LASTPIN (5900 2650) $PN 1
J 2
(5890 2660);
DISPLAY 0.617021 (5890 2660);
PAINT ORANGE (5890 2660);
FORCEPROP 2 LASTPIN (5900 2850) $PN 16
J 2
(5890 2860);
DISPLAY 0.617021 (5890 2860);
PAINT ORANGE (5890 2860);
FORCEPROP 1 LAST MATERIAL IC
J 0
(5950 3150);
DISPLAY 0.617021 (5950 3150);
PAINT SKYBLUE (5950 3150);
FORCEPROP 1 LAST LOCATION U8F2
J 0
(5950 3200);
DISPLAY 0.617021 (5950 3200);
PAINT AQUA (5950 3200);
FORCEPROP 2 LASTPIN (7000 2550) $PN 10
J 0
(7010 2560);
DISPLAY 0.617021 (7010 2560);
PAINT ORANGE (7010 2560);
FORCEPROP 2 LASTPIN (7000 2650) $PN 4
J 0
(7010 2660);
DISPLAY 0.617021 (7010 2660);
PAINT ORANGE (7010 2660);
FORCEPROP 2 LASTPIN (7000 2800) $PN 11
J 0
(7010 2810);
DISPLAY 0.617021 (7010 2810);
PAINT ORANGE (7010 2810);
FORCEPROP 2 LASTPIN (7000 2850) $PN 12
J 0
(7010 2860);
DISPLAY 0.617021 (7010 2860);
PAINT ORANGE (7010 2860);
FORCEPROP 2 LASTPIN (7000 2900) $PN 13
J 0
(7010 2910);
DISPLAY 0.617021 (7010 2910);
PAINT ORANGE (7010 2910);
FORCEPROP 2 LASTPIN (7000 2950) $PN 14
J 0
(7010 2960);
DISPLAY 0.617021 (7010 2960);
PAINT ORANGE (7010 2960);
FORCEPROP 1 LAST PART_NUMBER H12709-001
J 0
(5950 2425);
DISPLAY 0.617021 (5950 2425);
PAINT BLUE (5950 2425);
FORCEPROP 2 LASTPIN (7000 2700) $PN 5
J 0
(7010 2710);
DISPLAY 0.617021 (7010 2710);
PAINT ORANGE (7010 2710);
FORCEPROP 2 LASTPIN (7000 2750) $PN 6
J 0
(7010 2760);
DISPLAY 0.617021 (7010 2760);
PAINT ORANGE (7010 2760);
FORCEPROP 0 LAST ROOM BMC_BOOT_SPI
J 0
(5950 3300);
DISPLAY 1.021277 (5950 3300);
PAINT ORANGE (5950 3300);
DISPLAY INVISIBLE (5950 3300);
FORCEPROP 2 LAST CDS_LOCATION U8F2
J 0
(5950 3200);
DISPLAY 0.617021 (5950 3200);
PAINT AQUA (5950 3200);
DISPLAY INVISIBLE (5950 3200);
FORCEPROP 2 LAST SEC 1
J 0
(5950 3250);
DISPLAY 0.680851 (5950 3250);
PAINT MONO (5950 3250);
DISPLAY INVISIBLE (5950 3250);
FORCEPROP 0 LAST BOM_COST SM_MEM
J 0
(5950 3400);
DISPLAY 1.021277 (5950 3400);
PAINT ORANGE (5950 3400);
DISPLAY INVISIBLE (5950 3400);
FORCEPROP 2 LAST SEC_TYPE SKT16
J 0
(5950 3250);
DISPLAY 1.021277 (5950 3250);
PAINT ORANGE (5950 3250);
DISPLAY INVISIBLE (5950 3250);
FORCEPROP 1 LAST PACK_TYPE SKT16
J 0
(5950 3250);
PAINT SKYBLUE (5950 3250);
DISPLAY INVISIBLE (5950 3250);
FORCEPROP 1 LAST CDS_LMAN_SYM_OUTLINE -500,325,500,-325
J 0
(6450 2800);
DISPLAY 0.468085 (6450 2800);
PAINT GREEN (6450 2800);
DISPLAY INVISIBLE (6450 2800);
FORCEPROP 2 LAST CDS_LIB mstr_memory
J 0
(6450 2800);
PAINT ORANGE (6450 2800);
DISPLAY INVISIBLE (6450 2800);
FORCEPROP 1 LAST PATH I32
J 0
(6825 3151);
PAINT GREEN (6825 3151);
DISPLAY INVISIBLE (6825 3151);
FORCEADD GND..1
(4875 1750);
FORCEPROP 3 LASTPIN (4875 1800) SIG_NAME GND\g
J 0
(4885 1810);
DISPLAY 0.659574 (4885 1810);
PAINT MONO (4885 1810);
DISPLAY INVISIBLE (4885 1810);
FORCEPROP 1 LAST VOLTAGE 0.0V
J 0
(4830 1707);
DISPLAY 0.340426 (4830 1707);
PAINT SKYBLUE (4830 1707);
DISPLAY INVISIBLE (4830 1707);
FORCEPROP 1 LAST PATH I33
J 0
(4950 1750);
DISPLAY 0.872340 (4950 1750);
PAINT AQUA (4950 1750);
DISPLAY INVISIBLE (4950 1750);
FORCEPROP 2 LAST CDS_LIB mstr_symbols
J 0
(4875 1750);
PAINT ORANGE (4875 1750);
DISPLAY INVISIBLE (4875 1750);
FORCEPROP 1 LAST SIZE 1B
J 0
(4950 1700);
DISPLAY 0.872340 (4950 1700);
PAINT AQUA (4950 1700);
DISPLAY INVISIBLE (4950 1700);
FORCEPROP 1 LAST BODY_TYPE PLUMBING
J 0
(4830 1707);
DISPLAY 0.340426 (4830 1707);
PAINT GREEN (4830 1707);
DISPLAY INVISIBLE (4830 1707);
FORCEPROP 1 LAST HDL_POWER GND
J 0
(4875 1900);
DISPLAY 0.872340 (4875 1900);
PAINT GREEN (4875 1900);
DISPLAY INVISIBLE (4875 1900);
FORCEADD RES..2
R 2
(4550 3325);
FORCEPROP 1 LASTPIN (4550 3425) $PN 1
J 2
(4545 3387);
DISPLAY 0.787234 (4545 3387);
PAINT ORANGE (4545 3387);
FORCEPROP 1 LASTPIN (4550 3225) $PN 2
J 2
(4545 3235);
DISPLAY 0.787234 (4545 3235);
PAINT ORANGE (4545 3235);
FORCEPROP 1 LAST TOLERANCE 1%
J 2
(4505 3300);
DISPLAY 0.617021 (4505 3300);
PAINT SKYBLUE (4505 3300);
FORCEPROP 1 LAST LOCATION R8F13
J 2
(4505 3450);
DISPLAY 0.617021 (4505 3450);
PAINT AQUA (4505 3450);
FORCEPROP 1 LAST VALUE 4.75K
J 2
(4505 3400);
DISPLAY 0.617021 (4505 3400);
PAINT SKYBLUE (4505 3400);
FORCEPROP 1 LAST MATERIAL CHIP
J 2
(4510 3350);
DISPLAY 0.617021 (4510 3350);
PAINT SKYBLUE (4510 3350);
FORCEPROP 1 LAST WATTAGE 1/16W
J 2
(4510 3250);
DISPLAY 0.617021 (4510 3250);
PAINT SKYBLUE (4510 3250);
FORCEPROP 1 LAST PART_NUMBER G21796-072
J 2
(4510 3200);
DISPLAY 0.617021 (4510 3200);
PAINT BLUE (4510 3200);
FORCEPROP 1 LAST PACK_TYPE 0402
J 2
(4510 3150);
DISPLAY 0.617021 (4510 3150);
PAINT SKYBLUE (4510 3150);
FORCEPROP 2 LAST SEC_TYPE 0402
J 0
(4500 3550);
DISPLAY 1.021277 (4500 3550);
PAINT ORANGE (4500 3550);
DISPLAY INVISIBLE (4500 3550);
FORCEPROP 2 LAST SEC 1
J 0
(4500 3550);
PAINT MONO (4500 3550);
DISPLAY INVISIBLE (4500 3550);
FORCEPROP 2 LAST BOM_COST SM_MEM
J 0
(4525 3550);
DISPLAY 1.021277 (4525 3550);
PAINT ORANGE (4525 3550);
DISPLAY INVISIBLE (4525 3550);
FORCEPROP 2 LAST ROOM BMC_BOOT_SPI
J 0
(4525 3500);
DISPLAY 1.021277 (4525 3500);
PAINT ORANGE (4525 3500);
DISPLAY INVISIBLE (4525 3500);
FORCEPROP 2 LAST CDS_LIB mstr_discrete
J 0
(4550 3325);
PAINT ORANGE (4550 3325);
DISPLAY INVISIBLE (4550 3325);
FORCEPROP 1 LAST PATH I35
J 2
(4500 3500);
DISPLAY 0.978723 (4500 3500);
PAINT WHITE (4500 3500);
DISPLAY INVISIBLE (4500 3500);
FORCEPROP 2 LAST CDS_LOCATION R8F13
J 2
(4505 3450);
DISPLAY 0.617021 (4505 3450);
PAINT AQUA (4505 3450);
DISPLAY INVISIBLE (4505 3450);
FORCEADD GND..1
(7100 2350);
FORCEPROP 3 LASTPIN (7100 2400) SIG_NAME GND\g
J 0
(7110 2410);
DISPLAY 0.659574 (7110 2410);
PAINT MONO (7110 2410);
DISPLAY INVISIBLE (7110 2410);
FORCEPROP 1 LAST VOLTAGE 0
J 0
(7100 2350);
PAINT SKYBLUE (7100 2350);
DISPLAY INVISIBLE (7100 2350);
FORCEPROP 2 LAST CDS_LIB mstr_symbols
J 0
(7100 2350);
PAINT ORANGE (7100 2350);
DISPLAY INVISIBLE (7100 2350);
FORCEPROP 1 LAST SIZE 1B
J 0
(7175 2300);
DISPLAY 1.170213 (7175 2300);
PAINT GREEN (7175 2300);
DISPLAY INVISIBLE (7175 2300);
FORCEPROP 1 LAST PATH I6
J 0
(7175 2350);
DISPLAY 0.872340 (7175 2350);
PAINT AQUA (7175 2350);
DISPLAY INVISIBLE (7175 2350);
FORCEPROP 1 LAST BODY_TYPE PLUMBING
J 0
(7055 2307);
DISPLAY 0.340426 (7055 2307);
PAINT GREEN (7055 2307);
DISPLAY INVISIBLE (7055 2307);
FORCEPROP 1 LAST HDL_POWER GND
J 0
(7100 2500);
DISPLAY 1.170213 (7100 2500);
PAINT GREEN (7100 2500);
DISPLAY INVISIBLE (7100 2500);
FORCEADD RES..2
(5300 3300);
FORCEPROP 1 LAST TOLERANCE 1%
J 0
(5345 3275);
DISPLAY 0.617021 (5345 3275);
PAINT SKYBLUE (5345 3275);
FORCEPROP 1 LASTPIN (5300 3400) $PN 1
J 0
(5305 3362);
DISPLAY 0.617021 (5305 3362);
PAINT ORANGE (5305 3362);
FORCEPROP 1 LASTPIN (5300 3200) $PN 2
J 0
(5305 3210);
DISPLAY 0.617021 (5305 3210);
PAINT ORANGE (5305 3210);
FORCEPROP 1 LAST PACK_TYPE 0402
J 0
(5340 3125);
DISPLAY 0.617021 (5340 3125);
PAINT SKYBLUE (5340 3125);
FORCEPROP 1 LAST PART_NUMBER G21796-072
J 0
(5340 3175);
DISPLAY 0.617021 (5340 3175);
PAINT BLUE (5340 3175);
FORCEPROP 1 LAST WATTAGE 1/16W
J 0
(5340 3225);
DISPLAY 0.617021 (5340 3225);
PAINT SKYBLUE (5340 3225);
FORCEPROP 1 LAST MATERIAL EMPTY
J 0
(5340 3325);
DISPLAY 0.617021 (5340 3325);
PAINT RED (5340 3325);
FORCEPROP 1 LAST LOCATION R8F16
J 0
(5345 3425);
DISPLAY 0.617021 (5345 3425);
PAINT AQUA (5345 3425);
FORCEPROP 1 LAST VALUE 4.75K
J 0
(5395 3375);
DISPLAY 0.617021 (5395 3375);
PAINT SKYBLUE (5395 3375);
FORCEPROP 1 LAST PATH I8
J 0
(5350 3475);
DISPLAY 0.978723 (5350 3475);
PAINT WHITE (5350 3475);
DISPLAY INVISIBLE (5350 3475);
FORCEPROP 2 LAST SEC_TYPE 0402
J 2
(5350 3525);
DISPLAY 1.021277 (5350 3525);
PAINT ORANGE (5350 3525);
DISPLAY INVISIBLE (5350 3525);
FORCEPROP 2 LAST BOM_COST SM_MEM
J 2
(5325 3525);
DISPLAY 1.021277 (5325 3525);
PAINT ORANGE (5325 3525);
DISPLAY INVISIBLE (5325 3525);
FORCEPROP 2 LAST SEC 1
J 2
(5350 3525);
DISPLAY 0.680851 (5350 3525);
PAINT MONO (5350 3525);
DISPLAY INVISIBLE (5350 3525);
FORCEPROP 2 LAST ROOM BMC_BOOT_SPI
J 2
(5325 3475);
DISPLAY 1.021277 (5325 3475);
PAINT ORANGE (5325 3475);
DISPLAY INVISIBLE (5325 3475);
FORCEPROP 2 LAST CDS_LOCATION R8F16
J 0
(5345 3425);
DISPLAY 0.617021 (5345 3425);
PAINT AQUA (5345 3425);
DISPLAY INVISIBLE (5345 3425);
FORCEPROP 2 LAST CDS_LIB mstr_discrete
J 2
(5300 3300);
PAINT ORANGE (5300 3300);
DISPLAY INVISIBLE (5300 3300);
FORCEADD RES..2
R 2
(5100 3325);
FORCEPROP 1 LASTPIN (5100 3425) $PN 1
J 2
(5095 3387);
DISPLAY 0.617021 (5095 3387);
PAINT ORANGE (5095 3387);
FORCEPROP 1 LASTPIN (5100 3225) $PN 2
J 2
(5095 3235);
DISPLAY 0.617021 (5095 3235);
PAINT ORANGE (5095 3235);
FORCEPROP 1 LAST LOCATION R8F14
J 2
(5055 3450);
DISPLAY 0.617021 (5055 3450);
PAINT AQUA (5055 3450);
FORCEPROP 1 LAST VALUE 4.75K
J 2
(5055 3400);
DISPLAY 0.617021 (5055 3400);
PAINT SKYBLUE (5055 3400);
FORCEPROP 1 LAST MATERIAL CHIP
J 2
(5060 3350);
DISPLAY 0.617021 (5060 3350);
PAINT SKYBLUE (5060 3350);
FORCEPROP 1 LAST TOLERANCE 1%
J 2
(5055 3300);
DISPLAY 0.617021 (5055 3300);
PAINT SKYBLUE (5055 3300);
FORCEPROP 1 LAST WATTAGE 1/16W
J 2
(5060 3250);
DISPLAY 0.617021 (5060 3250);
PAINT SKYBLUE (5060 3250);
FORCEPROP 1 LAST PACK_TYPE 0402
J 2
(5060 3150);
DISPLAY 0.617021 (5060 3150);
PAINT SKYBLUE (5060 3150);
FORCEPROP 1 LAST PART_NUMBER G21796-072
J 2
(5060 3200);
DISPLAY 0.617021 (5060 3200);
PAINT BLUE (5060 3200);
FORCEPROP 2 LAST CDS_LIB mstr_discrete
J 0
(5100 3325);
PAINT ORANGE (5100 3325);
DISPLAY INVISIBLE (5100 3325);
FORCEPROP 2 LAST CDS_LOCATION R8F14
J 2
(5055 3450);
DISPLAY 0.617021 (5055 3450);
PAINT AQUA (5055 3450);
DISPLAY INVISIBLE (5055 3450);
FORCEPROP 2 LAST SEC 1
J 0
(5050 3550);
DISPLAY 0.680851 (5050 3550);
PAINT MONO (5050 3550);
DISPLAY INVISIBLE (5050 3550);
FORCEPROP 1 LAST PATH I9
J 2
(5050 3500);
DISPLAY 0.978723 (5050 3500);
PAINT WHITE (5050 3500);
DISPLAY INVISIBLE (5050 3500);
FORCEPROP 2 LAST ROOM BMC_BOOT_SPI
J 0
(5075 3500);
DISPLAY 1.021277 (5075 3500);
PAINT ORANGE (5075 3500);
DISPLAY INVISIBLE (5075 3500);
FORCEPROP 2 LAST BOM_COST SM_MEM
J 0
(5075 3550);
DISPLAY 1.021277 (5075 3550);
PAINT ORANGE (5075 3550);
DISPLAY INVISIBLE (5075 3550);
FORCEPROP 2 LAST SEC_TYPE 0402
J 0
(5050 3550);
DISPLAY 1.021277 (5050 3550);
PAINT ORANGE (5050 3550);
DISPLAY INVISIBLE (5050 3550);
FORCEADD BOM_NOTE..1
(8075 2550);
FORCEPROP 0 LAST L1 SOCKET IS D91187-001
J 0
(7925 2450);
DISPLAY 0.617021 (7925 2450);
PAINT WHITE (7925 2450);
FORCEPROP 2 LAST CDS_LIB mstr_symbols
J 0
(8075 2550);
PAINT WHITE (8075 2550);
DISPLAY INVISIBLE (8075 2550);
FORCEPROP 1 LAST COMMENT_BODY TRUE
J 0
(8100 2650);
DISPLAY 1.319149 (8100 2650);
PAINT WHITE (8100 2650);
DISPLAY INVISIBLE (8100 2650);
FORCEADD INTEL_CORP_BPAGE..1
(10700 375);
FORCEPROP 1 LAST CDS_CON_LAST_MODIFIED Fri Jun 16 17:49:00 2017
J 0
(9275 700);
PAINT ORANGE (9275 700);
DISPLAY INVISIBLE (9275 700);
FORCEPROP 1 LAST CUSTOM_TXT_CDS <CURRENT_DESIGN_SHEET> OF <TOTAL_DESIGN_SHEETS>
J 0
(10200 400);
PAINT ORANGE (10200 400);
FORCEPROP 1 LAST CUSTOM_TXT_CDS <CON_LAST_MODIFIED>
J 0
(6700 475);
PAINT ORANGE (6700 475);
FORCEPROP 2 LAST CUSTOM_TXT_CDS <XR_PAGE_TITLE>
J 0
(2810 5625);
DISPLAY 0.638298 (2810 5625);
PAINT PINK (2810 5625);
DISPLAY INVISIBLE (2810 5625);
FORCEPROP 1 LAST SCH_TITLE BMC DEDICATED SPI FLASH
J 0
(2750 425);
DISPLAY 1.212766 (2750 425);
PAINT ORANGE (2750 425);
FORCEPROP 2 LAST PAGE_BORDER TRUE
J 0
(2810 5625);
DISPLAY 0.617021 (2810 5625);
PAINT PINK (2810 5625);
DISPLAY INVISIBLE (2810 5625);
FORCEPROP 2 LAST CDS_LIB mstr_symbols
J 0
(10700 375);
PAINT MONO (10700 375);
DISPLAY INVISIBLE (10700 375);
FORCEPROP 1 LAST COMMENT_BODY TRUE
J 0
(10712 387);
DISPLAY 0.468085 (10712 387);
PAINT GREEN (10712 387);
DISPLAY INVISIBLE (10712 387);
FORCEPROP 2 LAST CDS_XR_PAGE_TITLE CR-162 : @BASEBOARD_FAB2_LIB.BASEBOARD_FAB2(SCH_1):PAGE162
J 0
(2810 5625);
DISPLAY 0.638298 (2810 5625);
PAINT PINK (2810 5625);
DISPLAY INVISIBLE (2810 5625);
FORCEADD DNS..2
(5305 3295);
PAINT RED (5305 3295);
FORCEPROP 2 LAST CDS_LIB mstr_misc
J 0
(5305 3295);
PAINT ORANGE (5305 3295);
DISPLAY INVISIBLE (5305 3295);
FORCEPROP 1 LAST COMMENT_BODY TRUE
R 1
J 0
(5380 3070);
DISPLAY 0.872340 (5380 3070);
PAINT GREEN (5380 3070);
DISPLAY INVISIBLE (5380 3070);
FORCEADD CAD_NOTE..1
(8075 3425);
FORCEPROP 0 LAST L1 PLACE CAPS NEAR VCC PIN ON W25Q128 COMPONENT
J 0
(7925 3300);
DISPLAY 1.021277 (7925 3300);
PAINT ORANGE (7925 3300);
FORCEPROP 2 LAST CDS_LIB mstr_symbols
J 0
(8075 3425);
PAINT ORANGE (8075 3425);
DISPLAY INVISIBLE (8075 3425);
FORCEPROP 1 LAST COMMENT_BODY TRUE
J 0
(8100 3525);
DISPLAY 0.978723 (8100 3525);
PAINT ORANGE (8100 3525);
DISPLAY INVISIBLE (8100 3525);
FORCEADD DNS..2
(4880 2045);
PAINT RED (4880 2045);
FORCEPROP 2 LAST CDS_LIB mstr_misc
J 0
(4880 2045);
PAINT ORANGE (4880 2045);
DISPLAY INVISIBLE (4880 2045);
FORCEPROP 1 LAST COMMENT_BODY TRUE
R 1
J 0
(4955 1820);
DISPLAY 0.872340 (4955 1820);
PAINT GREEN (4955 1820);
DISPLAY INVISIBLE (4955 1820);
FORCEADD CAD_NOTE..1
(8075 2850);
FORCEPROP 0 LAST L2 USE ALT SYMBOL ASSOCIATED WITH PART FOOTPRINT
J 0
(7925 2700);
DISPLAY 0.617021 (7925 2700);
PAINT WHITE (7925 2700);
FORCEPROP 0 LAST L1 THIS PART WILL BE IN SOCKET, PLEASE
J 0
(7925 2750);
DISPLAY 0.617021 (7925 2750);
PAINT WHITE (7925 2750);
FORCEPROP 2 LAST CDS_LIB mstr_symbols
J 0
(8075 2850);
PAINT WHITE (8075 2850);
DISPLAY INVISIBLE (8075 2850);
FORCEPROP 1 LAST COMMENT_BODY TRUE
J 0
(8100 2950);
DISPLAY 1.319149 (8100 2950);
PAINT WHITE (8100 2950);
DISPLAY INVISIBLE (8100 2950);
WIRE 16 -1 (5250 3650)(5250 3550);
WIRE 16 -1 (5250 3550)(5300 3550);
WIRE 16 -1 (5250 3550)(5100 3550);
WIRE 16 -1 (4825 3550)(5100 3550);
WIRE 16 -1 (5100 3425)(5100 3550);
WIRE 16 -1 (5725 3550)(5300 3550);
WIRE 16 -1 (5300 3400)(5300 3550);
WIRE 16 -1 (5725 3550)(5725 3000);
WIRE 16 -1 (5725 3550)(7350 3550);
WIRE 16 -1 (4550 3550)(4825 3550);
WIRE 16 -1 (4825 3425)(4825 3550);
WIRE 16 -1 (4550 3425)(4550 3550);
WIRE 16 -1 (7650 3550)(7350 3550);
WIRE 16 -1 (7350 3550)(7350 3500);
WIRE 16 -1 (5725 3000)(5900 3000);
WIRE 16 -1 (7650 3500)(7650 3550);
WIRE 16 -1 (7650 3125)(7650 3200);
WIRE 16 -1 (7650 3200)(7350 3200);
WIRE 16 -1 (7650 3300)(7650 3200);
WIRE 16 -1 (7350 3200)(7350 3300);
WIRE 16 -1 (4875 1800)(4875 1950);
WIRE 16 -1 (7100 2400)(7100 2550);
WIRE 16 -1 (7100 2550)(7000 2550);
WIRE 16 -1 (7475 2750)(7000 2750);
FORCEPROP 2 LAST SIG_NAME TP_SPI_2_2
J 0
(7065 2760);
DISPLAY 0.617021 (7065 2760);
PAINT ORANGE (7065 2760);
FORCEPROP 2 LASTPROP $XRERR UNIQUE?
J 0
(7505 2750);
DISPLAY 0.638298 (7505 2750);
PAINT MONO (7505 2750);
DISPLAY INVISIBLE (7505 2750);
WIRE 16 -1 (7475 2850)(7000 2850);
FORCEPROP 2 LAST SIG_NAME TP_SPI_2_4
J 0
(7065 2860);
DISPLAY 0.617021 (7065 2860);
PAINT ORANGE (7065 2860);
FORCEPROP 2 LASTPROP $XRERR UNIQUE?
J 0
(7505 2850);
DISPLAY 0.638298 (7505 2850);
PAINT MONO (7505 2850);
DISPLAY INVISIBLE (7505 2850);
WIRE 16 -1 (4250 2800)(4550 2800);
FORCEPROP 2 LAST SIG_NAME SPI_BMC_BT_CS_N
J 0
(4250 2810);
DISPLAY 0.617021 (4250 2810);
PAINT ORANGE (4250 2810);
WIRE 16 -1 (4550 3225)(4550 2800);
WIRE 16 -1 (4550 2800)(5900 2800);
WIRE 16 -1 (4250 2850)(5900 2850);
FORCEPROP 2 LAST SIG_NAME SPI_BMC_BT_CLK
J 0
(4250 2860);
DISPLAY 0.617021 (4250 2860);
PAINT ORANGE (4250 2860);
WIRE 16 -1 (5300 2900)(5900 2900);
WIRE 16 -1 (5300 3200)(5300 2900);
FORCEPROP 2 LAST SIG_NAME PU_SPI_FLASH_RESET_2_N
J 0
(5315 2910);
DISPLAY 0.617021 (5315 2910);
PAINT ORANGE (5315 2910);
FORCEPROP 2 LASTPROP $XRERR UNIQUE?
J 0
(5075 2910);
DISPLAY 0.638298 (5075 2910);
PAINT MONO (5075 2910);
DISPLAY INVISIBLE (5075 2910);
WIRE 16 -1 (7475 2800)(7000 2800);
FORCEPROP 2 LAST SIG_NAME TP_SPI_2_3
J 0
(7065 2810);
DISPLAY 0.617021 (7065 2810);
PAINT ORANGE (7065 2810);
FORCEPROP 2 LASTPROP $XRERR UNIQUE?
J 0
(7505 2800);
DISPLAY 0.638298 (7505 2800);
PAINT MONO (7505 2800);
DISPLAY INVISIBLE (7505 2800);
WIRE 16 -1 (7475 2900)(7000 2900);
FORCEPROP 2 LAST SIG_NAME TP_SPI_2_5
J 0
(7065 2910);
DISPLAY 0.617021 (7065 2910);
PAINT ORANGE (7065 2910);
FORCEPROP 2 LASTPROP $XRERR UNIQUE?
J 0
(7505 2900);
DISPLAY 0.638298 (7505 2900);
PAINT MONO (7505 2900);
DISPLAY INVISIBLE (7505 2900);
WIRE 16 -1 (4250 2550)(4975 2550);
FORCEPROP 2 LAST SIG_NAME SPI_BMC_BT_DI
J 0
(4250 2560);
DISPLAY 0.617021 (4250 2560);
PAINT ORANGE (4250 2560);
WIRE 16 -1 (7475 2650)(7000 2650);
FORCEPROP 2 LAST SIG_NAME TP_SPI_2_0
J 0
(7065 2660);
DISPLAY 0.617021 (7065 2660);
PAINT ORANGE (7065 2660);
FORCEPROP 2 LASTPROP $XRERR UNIQUE?
J 0
(7505 2650);
DISPLAY 0.638298 (7505 2650);
PAINT MONO (7505 2650);
DISPLAY INVISIBLE (7505 2650);
WIRE 16 -1 (7475 2950)(7000 2950);
FORCEPROP 2 LAST SIG_NAME TP_SPI_2_6
J 0
(7065 2960);
DISPLAY 0.617021 (7065 2960);
PAINT ORANGE (7065 2960);
FORCEPROP 2 LASTPROP $XRERR UNIQUE?
J 0
(7505 2950);
DISPLAY 0.638298 (7505 2950);
PAINT MONO (7505 2950);
DISPLAY INVISIBLE (7505 2950);
WIRE 3 2175 (4325 3600)(4700 3600);
WIRE 3 2175 (4700 3100)(4700 3600);
WIRE 3 2175 (4325 3100)(4325 3600);
WIRE 3 2175 (4325 3100)(4700 3100);
WIRE 16 -1 (5100 3225)(5100 2650);
WIRE 16 -1 (5100 2650)(5900 2650);
FORCEPROP 2 LAST SIG_NAME PU_SPI_BMC_BT_HOLD_N
J 0
(5190 2660);
DISPLAY 0.617021 (5190 2660);
PAINT ORANGE (5190 2660);
FORCEPROP 2 LASTPROP $XRERR UNIQUE?
J 0
(4950 2660);
DISPLAY 0.638298 (4950 2660);
PAINT MONO (4950 2660);
DISPLAY INVISIBLE (4950 2660);
WIRE 16 -1 (5900 2550)(5175 2550);
FORCEPROP 2 LAST SIG_NAME SPI_BMC_BT_DI_R
J 2
(5800 2560);
DISPLAY 0.617021 (5800 2560);
PAINT ORANGE (5800 2560);
FORCEPROP 2 LASTPROP $XRERR UNIQUE?
J 0
(5560 2560);
DISPLAY 0.638298 (5560 2560);
PAINT MONO (5560 2560);
DISPLAY INVISIBLE (5560 2560);
WIRE 16 -1 (4825 3225)(4825 2600);
WIRE 16 -1 (4825 2600)(4875 2600);
WIRE 16 -1 (4875 2600)(5900 2600);
FORCEPROP 2 LAST SIG_NAME PU_SPI_BMC_BT_WP_N
J 0
(4965 2610);
DISPLAY 0.617021 (4965 2610);
PAINT ORANGE (4965 2610);
FORCEPROP 2 LASTPROP $XRERR UNIQUE?
J 0
(4725 2610);
DISPLAY 0.638298 (4725 2610);
PAINT MONO (4725 2610);
DISPLAY INVISIBLE (4725 2610);
WIRE 16 -1 (4875 2150)(4875 2600);
WIRE 16 -1 (5900 2500)(4250 2500);
FORCEPROP 2 LAST SIG_NAME SPI_BMC_BT_DO
J 0
(4250 2510);
DISPLAY 0.617021 (4250 2510);
PAINT ORANGE (4250 2510);
WIRE 16 -1 (7475 2700)(7000 2700);
FORCEPROP 2 LAST SIG_NAME TP_SPI_2_1
J 0
(7065 2710);
DISPLAY 0.617021 (7065 2710);
PAINT ORANGE (7065 2710);
FORCEPROP 2 LASTPROP $XRERR UNIQUE?
J 0
(7505 2700);
DISPLAY 0.638298 (7505 2700);
PAINT MONO (7505 2700);
DISPLAY INVISIBLE (7505 2700);
DOT 1 (5100 3550);
DOT 1 (5250 3550);
DOT 1 (5300 3550);
DOT 1 (7650 3200);
DOT 1 (5725 3550);
DOT 1 (4550 2800);
DOT 1 (4875 2600);
DOT 1 (4825 3550);
DOT 1 (7350 3550);
FORCENOTE
U8F2 IS SOCKET.
(5950 2325) 0;
DISPLAY LEFT (5950 2325);
DISPLAY 1.021277 (5950 2325);
PAINT PURPLE (5950 2325);
FORCENOTE
TP FAB1 NOPOP R8F13  1215
(3875 3675) 0;
DISPLAY LEFT (3875 3675);
DISPLAY 1.021277 (3875 3675);
PAINT RED (3875 3675);
FORCENOTE
TP FAB POP R8F13 0227
(3875 3625) 0;
DISPLAY LEFT (3875 3625);
DISPLAY 1.021277 (3875 3625);
PAINT RED (3875 3625);
QUIT
